FILE_TYPE = CONNECTIVITY;
{Allegro Design Entry HDL 17.4-2019 S026 (4007227) 1/17/2022}
"PAGE_NUMBER" = 385;
0"NC";
1"P1V8_CPU0_RT_1D\g";
2"GND\g";
3"GND\g";
4"P1V8_CPU0_RT_1D\g";
5"GND\g";
6"GND\g";
7"GND\g";
8"P1V8_CPU0_RT_1D\g";
9"GND\g";
10"GND\g";
11"GND\g";
12"P1V8_CPU0_RT_1D\g";
13"GND\g";
14"GND\g";
15"GND\g";
16"SMB_RT_CPU0_P0_ROM_MUX_1D_SCL";
17"SMB_RT_CPU0_P0_ROM_MUX_1D_R_SCL";
18"SMB_RT_CPU0_P0_ROM_MUX_1D_SDA";
19"SMB_RT_CPU0_P0_ROM_MUX_1D_R_SDA";
20"RT_CPU0_P0_SCAN_MODE";
21"P1V8_CPU0_RT_1D\g";
22"JTAG_TMS_RT_CPU0_P0";
23"JTAG_TDI_RT_CPU0_P0";
24"JTAG_TCK_RT_CPU0_P0";
25"JTAG_TDO_RT_CPU0_P0";
26"RST_RT_CPU0_P0_RESET_R_N";
27"JTAG_TDO_RT_CPU0_P0";
28"JTAG_TCK_RT_CPU0_P0";
29"JTAG_TRST_RT_CPU0_P0_N";
30"JTAG_TDI_RT_CPU0_P0";
31"JTAG_TMS_RT_CPU0_P0";
32"GPIO3_RT_CPU0_P0";
33"RST_RT_CPU0_P0_RESET_N";
34"P1V8_CPU0_RT_1D\g";
35"GND\g";
36"GND\g";
37"P1V8_CPU0_RT_1D\g";
38"RST_RT_CPU0_P0_PERST_R_N";
39"JTAG_TEST_MODE_RT_CPU0_P0";
40"MODE_RT_CPU0_P0";
41"RT_CPU0_P0_SCAN_MODE";
42"RXDET_BYP_RT_CPU0_P0";
43"RXDET_BYP_RT_CPU0_P0";
44"CLKREQ_RT_CPU0_P0_N";
45"RST_RT_CPU0_P0_PERST_N";
46"JTAG_TEST_MODE_RT_CPU0_P0";
47"TEST2_RT_CPU0_P0";
48"TEST0_RT_CPU0_P0";
49"GPIO2_RT_CPU0_P0";
50"MODE_RT_CPU0_P0";
51"RT_CPU0_P0_ADDR2";
52"GPIO2_RT_CPU0_P0";
53"CLK_100M_RETIMER_CPU0_P0_DN";
54"CLK_100M_RETIMER_CPU0_P0_DP";
55"RT_CPU0_P0_ADDR1";
56"RT_CPU0_P0_ADDR2";
57"RT_CPU0_P0_ADDR3";
58"SMB_RT_CPU0_P0_R2_SCL";
59"SMB_RT_CPU0_P0_R2_SDA";
60"TEST0_RT_CPU0_P0";
61"TEST1_RT_CPU0_P0";
62"TEST2_RT_CPU0_P0";
63"TEST1_RT_CPU0_P0";
64"RT_CPU0_P0_ADDR3";
65"GPIO3_RT_CPU0_P0";
66"SMB_RT_CPU0_P0_R_SDA";
67"SMB_RT_CPU0_P0_R_SCL";
68"RT_CPU0_P0_ADDR1";
69"RST_RT_CPU0_P0_RESET_R_N";
70"RST_RT_CPU0_P0_PERST_R_N";
71"CLK_100M_RETIMER_CPU0_P0_R_DP";
72"CLK_100M_RETIMER_CPU0_P0_R_DN";
%"P1V0"
"1","(-1475,6250)","0","pure_quanta_power","I101";
;
HDL_POWER"P1V8_CPU0_RT_1D"
CDS_LIB"pure_quanta_power";
"A"1;
%"Q_RES"
"1","(-2700,3200)","0","pure_quanta","I111";
;
LOCATION"R1364"
$SEC"1"
CDS_SEC"1"
VALUE"1K"
PACK_TYPE"0201LF"
MATERIAL"CHIP"
CDS_LIB"pure_quanta"
WATTAGE"1/20W"
TOLERANCE"1%"
PART_NUMBER"CS21001FE07";
"B"
$PN"2"2;
"A"
$PN"1"29;
%"UNIVERSAL_GND"
"1","(-1950,3200)","1","pure_quanta_power","I112";
;
CDS_LIB"pure_quanta_power"
HDL_POWER"GND";
"A"2;
%"Q_RES"
"2","(-1350,3350)","0","pure_quanta","I114";
;
LOCATION"R1370"
$SEC"1"
CDS_SEC"1"
TOLERANCE"1%"
MATERIAL"CHIP"
PACK_TYPE"0201LF"
WATTAGE"1/20W"
VALUE"10K"
CDS_LIB"pure_quanta"
PART_NUMBER"CS31001FE17";
"A"
$PN"1"43;
"B"
$PN"2"3;
%"GND"
"1","(-1350,2950)","0","pure_quanta_power","I115";
;
CDS_LIB"pure_quanta_power"
SIZE"1B"
BOM_COST"MEM"
HDL_POWER"GND";
"A<SIZE-1..0>\NAC"3;
%"Q_RES"
"2","(-1350,3875)","0","pure_quanta","I116";
;
LOCATION"R1369"
$SEC"1"
CDS_SEC"1"
TOLERANCE"1%"
PACK_TYPE"0201LF"
VALUE"1K"
MATERIAL"EMPTY"
WATTAGE"1/20W"
CDS_LIB"pure_quanta"
PART_NUMBER"CS21001FE07";
"A"
$PN"1"4;
"B"
$PN"2"43;
%"P1V0"
"1","(-1350,4275)","0","pure_quanta_power","I117";
;
HDL_POWER"P1V8_CPU0_RT_1D"
CDS_LIB"pure_quanta_power";
"A"4;
%"Q_RES"
"1","(-2675,2250)","0","pure_quanta","I119";
;
LOCATION"R1368"
$SEC"1"
CDS_SEC"1"
VALUE"4.7K"
MATERIAL"CHIP"
PACK_TYPE"0201LF"
WATTAGE"1/20W"
TOLERANCE"5%"
CDS_LIB"pure_quanta"
PART_NUMBER"CS24701JE04";
"B"
$PN"2"5;
"A"
$PN"1"44;
%"UNIVERSAL_GND"
"1","(-1950,2250)","1","pure_quanta_power","I120";
;
CDS_LIB"pure_quanta_power"
HDL_POWER"GND";
"A"5;
%"Q_RES"
"2","(-8975,3400)","0","pure_quanta","I121";
;
LOCATION"R973"
$SEC"1"
CDS_SEC"1"
PACK_TYPE"0201LF"
WATTAGE"1/20W"
TOLERANCE"1%"
VALUE"200"
MATERIAL"CHIP"
CDS_LIB"pure_quanta"
PART_NUMBER"CS12001FE12";
"A"
$PN"1"20;
"B"
$PN"2"7;
%"Q_RES"
"2","(-650,825)","0","pure_quanta","I123";
;
LOCATION"R1365"
$SEC"1"
CDS_SEC"1"
PACK_TYPE"0201LF"
MATERIAL"CHIP"
TOLERANCE"5%"
VALUE"4.7K"
WATTAGE"1/20W"
CDS_LIB"pure_quanta"
PART_NUMBER"CS24701JE04";
"A"
$PN"1"24;
"B"
$PN"2"6;
%"GND"
"1","(-650,525)","0","pure_quanta_power","I128";
;
SIZE"1B"
BOM_COST"MEM"
CDS_LIB"pure_quanta_power"
HDL_POWER"GND";
"A<SIZE-1..0>\NAC"6;
%"Q_RES"
"2","(-650,1475)","0","pure_quanta","I143";
;
LOCATION"R1446"
$SEC"1"
CDS_SEC"1"
VALUE"4.7K"
TOLERANCE"5%"
WATTAGE"1/20W"
MATERIAL"EMPTY"
PACK_TYPE"0201LF"
CDS_LIB"pure_quanta"
PART_NUMBER"CS24701JE04";
"A"
$PN"1"21;
"B"
$PN"2"24;
%"P1V0"
"1","(-650,1775)","0","pure_quanta_power","I144";
;
HDL_POWER"P1V8_CPU0_RT_1D"
CDS_LIB"pure_quanta_power";
"A"21;
%"Q_RES"
"2","(-925,1450)","0","pure_quanta","I145";
;
LOCATION"R1445"
$SEC"1"
CDS_SEC"1"
TOLERANCE"1%"
VALUE"1K"
PACK_TYPE"0201LF"
WATTAGE"1/20W"
MATERIAL"EMPTY"
CDS_LIB"pure_quanta"
PART_NUMBER"CS21001FE07";
"A"
$PN"1"21;
"B"
$PN"2"25;
%"Q_RES"
"2","(-1200,1450)","0","pure_quanta","I146";
;
LOCATION"R1439"
$SEC"1"
CDS_SEC"1"
WATTAGE"1/20W"
TOLERANCE"5%"
VALUE"4.7K"
PACK_TYPE"0201LF"
MATERIAL"EMPTY"
CDS_LIB"pure_quanta"
PART_NUMBER"CS24701JE04";
"A"
$PN"1"21;
"B"
$PN"2"22;
%"Q_RES"
"2","(-1475,1450)","0","pure_quanta","I147";
;
LOCATION"R1438"
$SEC"1"
CDS_SEC"1"
TOLERANCE"5%"
WATTAGE"1/20W"
VALUE"4.7K"
PACK_TYPE"0201LF"
MATERIAL"EMPTY"
CDS_LIB"pure_quanta"
PART_NUMBER"CS24701JE04";
"A"
$PN"1"21;
"B"
$PN"2"23;
%"UNIVERSAL_GND"
"1","(-8975,3125)","0","pure_quanta_power","I23";
;
CDS_LIB"pure_quanta_power"
HDL_POWER"GND";
"A"7;
%"Q_RES"
"2","(-8975,4075)","0","pure_quanta","I25";
;
LOCATION"R972"
$SEC"1"
CDS_SEC"1"
PACK_TYPE"0201LF"
MATERIAL"EMPTY"
VALUE"4.7K"
WATTAGE"1/20W"
TOLERANCE"5%"
CDS_LIB"pure_quanta"
PART_NUMBER"CS24701JE04";
"A"
$PN"1"8;
"B"
$PN"2"20;
%"P1V0"
"1","(-8975,4400)","0","pure_quanta_power","I26";
;
HDL_POWER"P1V8_CPU0_RT_1D"
CDS_LIB"pure_quanta_power";
"A"8;
%"Q_RES"
"2","(-8950,5000)","0","pure_quanta","I27";
;
LOCATION"R979"
$SEC"1"
CDS_SEC"1"
WATTAGE"1/20W"
VALUE"10K"
TOLERANCE"1%"
PACK_TYPE"0201LF"
MATERIAL"CHIP"
CDS_LIB"pure_quanta"
PART_NUMBER"CS31001FE17";
"A"
$PN"1"49;
"B"
$PN"2"35;
%"Q_RES"
"2","(-8650,5000)","0","pure_quanta","I28";
;
LOCATION"R980"
$SEC"1"
CDS_SEC"1"
PACK_TYPE"0201LF"
MATERIAL"CHIP"
WATTAGE"1/20W"
TOLERANCE"1%"
VALUE"10K"
CDS_LIB"pure_quanta"
PART_NUMBER"CS31001FE17";
"A"
$PN"1"65;
"B"
$PN"2"35;
%"Q_RES"
"2","(-8325,5000)","0","pure_quanta","I29";
;
LOCATION"R982"
$SEC"1"
CDS_SEC"1"
TOLERANCE"5%"
VALUE"4.7K"
PACK_TYPE"0201LF"
WATTAGE"1/20W"
MATERIAL"CHIP"
CDS_LIB"pure_quanta"
PART_NUMBER"CS24701JE04";
"A"
$PN"1"48;
"B"
$PN"2"35;
%"Q_RES"
"2","(-8950,5950)","0","pure_quanta","I30";
;
LOCATION"R978"
$SEC"1"
CDS_SEC"1"
TOLERANCE"5%"
VALUE"4.7K"
WATTAGE"1/20W"
MATERIAL"EMPTY"
PACK_TYPE"0201LF"
CDS_LIB"pure_quanta"
PART_NUMBER"CS24701JE04";
"A"
$PN"1"34;
"B"
$PN"2"49;
%"Q_RES"
"2","(-8325,5950)","0","pure_quanta","I31";
;
LOCATION"R981"
$SEC"1"
CDS_SEC"1"
MATERIAL"EMPTY"
WATTAGE"1/20W"
PACK_TYPE"0201LF"
TOLERANCE"5%"
VALUE"4.7K"
CDS_LIB"pure_quanta"
PART_NUMBER"CS24701JE04";
"A"
$PN"1"34;
"B"
$PN"2"48;
%"P1V0"
"1","(-8950,6350)","0","pure_quanta_power","I32";
;
HDL_POWER"P1V8_CPU0_RT_1D"
CDS_LIB"pure_quanta_power";
"A"34;
%"UNIVERSAL_GND"
"1","(-6300,350)","0","pure_quanta_power","I35";
;
CDS_LIB"pure_quanta_power"
HDL_POWER"GND";
"A"9;
%"UNIVERSAL_GND"
"1","(-6150,350)","0","pure_quanta_power","I36";
;
CDS_LIB"pure_quanta_power"
HDL_POWER"GND";
"A"10;
%"Q_RES"
"2","(-6300,675)","2","pure_quanta","I37";
;
LOCATION"R623"
$SEC"1"
CDS_SEC"1"
WATTAGE"1/20W"
MATERIAL"EMPTY"
PACK_TYPE"0201LF"
VALUE"51.1"
TOLERANCE"1%"
CDS_LIB"pure_quanta"
PART_NUMBER"CS05111FE00";
"A"
$PN"1"53;
"B"
$PN"2"9;
%"Q_RES"
"2","(-6150,675)","0","pure_quanta","I38";
;
LOCATION"R624"
$SEC"1"
CDS_SEC"1"
VALUE"51.1"
MATERIAL"EMPTY"
WATTAGE"1/20W"
TOLERANCE"1%"
PACK_TYPE"0201LF"
CDS_LIB"pure_quanta"
PART_NUMBER"CS05111FE00";
"A"
$PN"1"54;
"B"
$PN"2"10;
%"Q_RES"
"1","(-6600,1150)","0","pure_quanta","I39";
;
LOCATION"R595"
SEC"1"
PACK_TYPE"0201LF"
MATERIAL"CHIP"
TOLERANCE"5%"
VALUE"0"
WATTAGE"1/20W"
SEC_TYPE"0201LF"
CDS_LIB"pure_quanta"
PART_NUMBER"CS00001JE10";
"B"
$PN"2"54;
"A"
$PN"1"71;
%"Q_RES"
"1","(-6600,1000)","0","pure_quanta","I40";
;
LOCATION"R596"
SEC"1"
MATERIAL"CHIP"
PACK_TYPE"0201LF"
SEC_TYPE"0201LF"
WATTAGE"1/20W"
VALUE"0"
TOLERANCE"5%"
CDS_LIB"pure_quanta"
PART_NUMBER"CS00001JE10";
"B"
$PN"2"53;
"A"
$PN"1"72;
%"Q_RES"
"1","(-6325,1500)","0","pure_quanta","I41";
;
LOCATION"R667"
$SEC"1"
CDS_SEC"1"
PACK_TYPE"0201LF"
WATTAGE"1/20W"
MATERIAL"CHIP"
CDS_LIB"pure_quanta"
VALUE"49.9"
TOLERANCE"1%"
PART_NUMBER"CS04991FE06";
"B"
$PN"2"19;
"A"
$PN"1"18;
%"Q_RES"
"1","(-6325,1600)","0","pure_quanta","I42";
;
LOCATION"R666"
$SEC"1"
CDS_SEC"1"
MATERIAL"CHIP"
WATTAGE"1/20W"
PACK_TYPE"0201LF"
VALUE"49.9"
TOLERANCE"1%"
CDS_LIB"pure_quanta"
PART_NUMBER"CS04991FE06";
"B"
$PN"2"17;
"A"
$PN"1"16;
%"Q_RES"
"1","(-6350,2750)","0","pure_quanta","I49";
;
LOCATION"R977"
$SEC"1"
CDS_SEC"1"
CDS_LIB"pure_quanta"
PACK_TYPE"0201LF"
MATERIAL"CHIP"
TOLERANCE"5%"
VALUE"0"
WATTAGE"1/20W"
PART_NUMBER"CS00001JE10";
"B"
$PN"2"59;
"A"
$PN"1"66;
%"Q_RES"
"1","(-6350,2850)","0","pure_quanta","I50";
;
LOCATION"R976"
$SEC"1"
CDS_SEC"1"
WATTAGE"1/20W"
TOLERANCE"5%"
VALUE"0"
MATERIAL"CHIP"
PACK_TYPE"0201LF"
CDS_LIB"pure_quanta"
PART_NUMBER"CS00001JE10";
"B"
$PN"2"58;
"A"
$PN"1"67;
%"PT5161LRS"
"3","(-4375,2300)","0","pure_quanta","I53";
;
LOCATION"U6010"
$SEC"3"
CDS_SEC"3"
PART_TYPE"SMLF"
VALUE"PT5161LRS"
MATERIAL"IC"
CDS_LIB"pure_quanta"
CDS_LMAN_SYM_OUTLINE"-500,1450,450,-1400"
NEEDS_NO_SIZE"TRUE"
PART_NUMBER"AJ051610U03";
"EE_DAT"
$PN"FJ3"19;
"EE_CLK"
$PN"FF5"17;
"CLKREQ_N \B"
$PN"G35"44;
"TEST2"
$PN"FF30"62;
"TEST1"
$PN"FF27"61;
"TEST0"
$PN"FF24"60;
"T_SENSE"
$PN"E30"13;
"SMBDAT"
$PN"B28"59;
"SMBCLK"
$PN"B31"58;
"SMB_ADDR3"
$PN"B25"57;
"SMB_ADDR2"
$PN"B23"56;
"SMB_ADDR1"
$PN"F34"55;
"SCAN_MODE"
$PN"FF33"41;
"RXDET_BYP"
$PN"E11"42;
"RESET_N \B"
$PN"FF11"33;
"REFCLKP"
$PN"FJ16"54;
"REFCLKN"
$PN"FF18"53;
"REFCLK_OUTP"
$PN"B16"0;
"REFCLK_OUTN"
$PN"E18"0;
"PERST_N \B"
$PN"F2"45;
"MODE"
$PN"FJ9"40;
"JTAG_TRST_N \B"
$PN"E8"29;
"JTAG_TMS"
$PN"B12"31;
"JTAG_TEST_MODE"
$PN"FF8"39;
"JTAG_TDO"
$PN"B9"27;
"JTAG_TDI"
$PN"B6"30;
"JTAG_TCK"
$PN"B3"28;
"INT_N \B"
$PN"FJ31"0;
"GPIO3"
$PN"FJ28"32;
"GPIO2"
$PN"FJ25"52;
"GPIO1"
$PN"FJ23"0;
"GPIO0"
$PN"FJ6"0;
%"Q_RES"
"2","(-8025,4975)","0","pure_quanta","I57";
;
LOCATION"R984"
$SEC"1"
CDS_SEC"1"
MATERIAL"CHIP"
WATTAGE"1/20W"
TOLERANCE"5%"
VALUE"4.7K"
PACK_TYPE"0201LF"
CDS_LIB"pure_quanta"
PART_NUMBER"CS24701JE04";
"A"
$PN"1"63;
"B"
$PN"2"35;
%"Q_RES"
"2","(-7725,4975)","0","pure_quanta","I58";
;
LOCATION"R995"
$SEC"1"
CDS_SEC"1"
MATERIAL"CHIP"
WATTAGE"1/20W"
TOLERANCE"5%"
PACK_TYPE"0201LF"
VALUE"4.7K"
CDS_LIB"pure_quanta"
PART_NUMBER"CS24701JE04";
"A"
$PN"1"47;
"B"
$PN"2"35;
%"UNIVERSAL_GND"
"1","(-7425,4500)","0","pure_quanta_power","I59";
;
CDS_LIB"pure_quanta_power"
HDL_POWER"GND";
"A"35;
%"Q_RES"
"2","(-7425,4950)","0","pure_quanta","I60";
;
LOCATION"R997"
$SEC"1"
CDS_SEC"1"
TOLERANCE"5%"
PACK_TYPE"0201LF"
WATTAGE"1/20W"
MATERIAL"CHIP"
VALUE"4.7K"
CDS_LIB"pure_quanta"
PART_NUMBER"CS24701JE04";
"A"
$PN"1"46;
"B"
$PN"2"35;
%"Q_RES"
"2","(-8025,5900)","0","pure_quanta","I61";
;
LOCATION"R983"
$SEC"1"
CDS_SEC"1"
PACK_TYPE"0201LF"
MATERIAL"EMPTY"
VALUE"4.7K"
TOLERANCE"5%"
WATTAGE"1/20W"
CDS_LIB"pure_quanta"
PART_NUMBER"CS24701JE04";
"A"
$PN"1"34;
"B"
$PN"2"63;
%"Q_RES"
"2","(-7725,5925)","0","pure_quanta","I62";
;
LOCATION"R985"
$SEC"1"
CDS_SEC"1"
WATTAGE"1/20W"
VALUE"4.7K"
TOLERANCE"5%"
PACK_TYPE"0201LF"
MATERIAL"EMPTY"
CDS_LIB"pure_quanta"
PART_NUMBER"CS24701JE04";
"A"
$PN"1"34;
"B"
$PN"2"47;
%"Q_RES"
"2","(-7425,5950)","0","pure_quanta","I63";
;
LOCATION"R975"
$SEC"1"
CDS_SEC"1"
WATTAGE"1/20W"
PACK_TYPE"0201LF"
MATERIAL"EMPTY"
TOLERANCE"5%"
VALUE"4.7K"
CDS_LIB"pure_quanta"
PART_NUMBER"CS24701JE04";
"A"
$PN"1"34;
"B"
$PN"2"46;
%"UNIVERSAL_GND"
"1","(-5025,5150)","0","pure_quanta_power","I70";
;
CDS_LIB"pure_quanta_power"
HDL_POWER"GND";
"A"11;
%"Q_RES"
"2","(-5025,5500)","0","pure_quanta","I71";
;
LOCATION"R1001"
$SEC"1"
CDS_SEC"1"
TOLERANCE"5%"
WATTAGE"1/20W"
VALUE"4.7K"
PACK_TYPE"0201LF"
MATERIAL"EMPTY"
CDS_LIB"pure_quanta"
PART_NUMBER"CS24701JE04";
"A"
$PN"1"50;
"B"
$PN"2"11;
%"Q_RES"
"2","(-5025,6025)","0","pure_quanta","I72";
;
LOCATION"R998"
$SEC"1"
CDS_SEC"1"
PACK_TYPE"0201LF"
MATERIAL"CHIP"
VALUE"4.7K"
TOLERANCE"5%"
WATTAGE"1/20W"
CDS_LIB"pure_quanta"
PART_NUMBER"CS24701JE04";
"A"
$PN"1"12;
"B"
$PN"2"50;
%"P1V0"
"1","(-5025,6350)","0","pure_quanta_power","I74";
;
HDL_POWER"P1V8_CPU0_RT_1D"
CDS_LIB"pure_quanta_power";
"A"12;
%"UNIVERSAL_GND"
"1","(-3375,1650)","1","pure_quanta_power","I75";
;
CDS_LIB"pure_quanta_power"
HDL_POWER"GND";
"A"13;
%"Q_RES"
"1","(-2575,2150)","0","pure_quanta","I76";
;
LOCATION"R953"
SEC"1"
VALUE"0"
PACK_TYPE"0201LF"
WATTAGE"1/20W"
TOLERANCE"5%"
MATERIAL"CHIP"
SEC_TYPE"0201LF"
CDS_LIB"pure_quanta"
PART_NUMBER"CS00001JE10";
"B"
$PN"2"38;
"A"
$PN"1"45;
%"Q_RES"
"1","(-2575,2050)","0","pure_quanta","I77";
;
LOCATION"R963"
$SEC"1"
CDS_SEC"1"
VALUE"0"
PACK_TYPE"0201LF"
CDS_LIB"pure_quanta"
MATERIAL"CHIP"
TOLERANCE"5%"
WATTAGE"1/20W"
PART_NUMBER"CS00001JE10";
"B"
$PN"2"26;
"A"
$PN"1"33;
%"UNIVERSAL_GND"
"1","(-3475,4750)","0","pure_quanta_power","I85";
;
CDS_LIB"pure_quanta_power"
HDL_POWER"GND";
"A"36;
%"Q_RES"
"2","(-3475,5175)","0","pure_quanta","I86";
;
LOCATION"R965"
$SEC"1"
CDS_SEC"1"
PACK_TYPE"0201LF"
MATERIAL"EMPTY"
WATTAGE"1/20W"
VALUE"1K"
TOLERANCE"1%"
CDS_LIB"pure_quanta"
PART_NUMBER"CS21001FE07";
"A"
$PN"1"64;
"B"
$PN"2"36;
%"Q_RES"
"2","(-3175,5175)","0","pure_quanta","I87";
;
LOCATION"R967"
$SEC"1"
CDS_SEC"1"
MATERIAL"CHIP"
VALUE"20K"
PACK_TYPE"0201LF"
TOLERANCE"1%"
WATTAGE"1/20W"
CDS_LIB"pure_quanta"
PART_NUMBER"CS32001FE00";
"A"
$PN"1"51;
"B"
$PN"2"36;
%"Q_RES"
"2","(-3475,5950)","0","pure_quanta","I88";
;
LOCATION"R964"
$SEC"1"
CDS_SEC"1"
VALUE"1K"
MATERIAL"CHIP"
WATTAGE"1/20W"
TOLERANCE"1%"
PACK_TYPE"0201LF"
CDS_LIB"pure_quanta"
PART_NUMBER"CS21001FE07";
"A"
$PN"1"37;
"B"
$PN"2"64;
%"Q_RES"
"2","(-3175,5950)","0","pure_quanta","I89";
;
LOCATION"R966"
$SEC"1"
CDS_SEC"1"
WATTAGE"1/20W"
VALUE"1K"
MATERIAL"EMPTY"
TOLERANCE"1%"
PACK_TYPE"0201LF"
CDS_LIB"pure_quanta"
PART_NUMBER"CS21001FE07";
"A"
$PN"1"37;
"B"
$PN"2"51;
%"Q_RES"
"2","(-2825,5175)","0","pure_quanta","I90";
;
LOCATION"R969"
$SEC"1"
CDS_SEC"1"
WATTAGE"1/20W"
MATERIAL"CHIP"
PACK_TYPE"0201LF"
TOLERANCE"1%"
VALUE"1K"
CDS_LIB"pure_quanta"
PART_NUMBER"CS21001FE07";
"A"
$PN"1"68;
"B"
$PN"2"36;
%"Q_RES"
"2","(-2825,5925)","0","pure_quanta","I91";
;
LOCATION"R968"
$SEC"1"
CDS_SEC"1"
WATTAGE"1/20W"
PACK_TYPE"0201LF"
VALUE"1K"
TOLERANCE"1%"
MATERIAL"EMPTY"
CDS_LIB"pure_quanta"
PART_NUMBER"CS21001FE07";
"A"
$PN"1"37;
"B"
$PN"2"68;
%"P1V0"
"1","(-3475,6375)","0","pure_quanta_power","I92";
;
HDL_POWER"P1V8_CPU0_RT_1D"
CDS_LIB"pure_quanta_power";
"A"37;
%"GND"
"1","(-1475,4800)","0","pure_quanta_power","I93";
;
SIZE"1B"
BOM_COST"MEM"
CDS_LIB"pure_quanta_power"
HDL_POWER"GND";
"A<SIZE-1..0>\NAC"14;
%"GND"
"1","(-1300,4825)","0","pure_quanta_power","I94";
;
SIZE"1B"
BOM_COST"MEM"
CDS_LIB"pure_quanta_power"
HDL_POWER"GND";
"A<SIZE-1..0>\NAC"15;
%"Q_RES"
"2","(-1475,5175)","2","pure_quanta","I96";
;
LOCATION"R971"
$SEC"1"
CDS_SEC"1"
VALUE"10K"
TOLERANCE"1%"
MATERIAL"CHIP"
WATTAGE"1/20W"
PACK_TYPE"0201LF"
CDS_LIB"pure_quanta"
PART_NUMBER"CS31001FE17";
"A"
$PN"1"69;
"B"
$PN"2"14;
%"Q_RES"
"2","(-1300,5175)","0","pure_quanta","I97";
;
LOCATION"R970"
$SEC"1"
CDS_SEC"1"
PACK_TYPE"0201LF"
MATERIAL"CHIP"
WATTAGE"1/20W"
VALUE"10K"
TOLERANCE"1%"
CDS_LIB"pure_quanta"
PART_NUMBER"CS31001FE17";
"A"
$PN"1"70;
"B"
$PN"2"15;
%"Q_RES"
"2","(-1475,6000)","2","pure_quanta","I98";
;
LOCATION"R974"
$SEC"1"
CDS_SEC"1"
MATERIAL"EMPTY"
WATTAGE"1/20W"
VALUE"4.7K"
TOLERANCE"5%"
PACK_TYPE"0201LF"
CDS_LIB"pure_quanta"
PART_NUMBER"CS24701JE04";
"A"
$PN"1"1;
"B"
$PN"2"69;
END.
